(kicad_pcb
	(version 20240108)
	(generator "pcbnew")
	(generator_version "8.0")
	(general
		(thickness 1.62)
		(legacy_teardrops no)
	)
	(paper "A4")
	(title_block
		(title "Jetson Orin Baseboard")
		(date "2025-03-12")
		(rev "1.3.4")
		(company "Antmicro Ltd")
		(comment 1 "www.antmicro.com")
		(comment 9 "footprints 505-510 of 677")
	)
	(layers
		(0 "F.Cu" signal)
		(1 "In1.Cu" signal)
		(2 "In2.Cu" signal)
		(3 "In3.Cu" signal)
		(4 "In4.Cu" jumper)
		(5 "In5.Cu" signal)
		(6 "In6.Cu" signal)
		(31 "B.Cu" signal)
		(32 "B.Adhes" user "B.Adhesive")
		(33 "F.Adhes" user "F.Adhesive")
		(34 "B.Paste" user)
		(35 "F.Paste" user)
		(36 "B.SilkS" user "B.Silkscreen")
		(37 "F.SilkS" user "F.Silkscreen")
		(38 "B.Mask" user)
		(39 "F.Mask" user)
		(40 "Dwgs.User" user "User.Drawings")
		(41 "Cmts.User" user "User.Comments")
		(42 "Eco1.User" user "User.Eco1")
		(43 "Eco2.User" user "User.Eco2")
		(44 "Edge.Cuts" user)
		(45 "Margin" user)
		(46 "B.CrtYd" user "B.Courtyard")
		(47 "F.CrtYd" user "F.Courtyard")
		(48 "B.Fab" user)
		(49 "F.Fab" user)
	)
	(footprint "antmicro-footprints:R_0402_1005Metric"
		(layer "B.Cu")
		(at 138.65 117.55)
		(descr "Resistor SMD 0402")
		(tags "resistor SMD 0402")
		(property "Reference" "R6"
			(at 0.7 1.3 180)
			(layer "B.SilkS")
			(effects
				(font
					(size 0.7 0.7)
					(thickness 0.15)
				)
				(justify left bottom mirror)
			)
		)
		(property "Value" "R_100k_0402"
			(at 0 -1.4 180)
			(layer "B.Fab")
			(effects
				(font
					(size 0.7 0.7)
					(thickness 0.15)
				)
				(justify left bottom mirror)
			)
		)
		(property "Footprint" "antmicro-footprints:R_0402_1005Metric"
			(at 0 0 0)
			(layer "F.Fab")
			(hide yes)
			(effects
				(font
					(size 1.27 1.27)
					(thickness 0.15)
				)
			)
		)
		(property "Datasheet" "https://www.bourns.com/docs/product-datasheets/cr.pdf"
			(at 0 0 0)
			(layer "F.Fab")
			(hide yes)
			(effects
				(font
					(size 1.27 1.27)
					(thickness 0.15)
				)
			)
		)
		(property "Author" "Antmicro"
			(at 0 0 0)
			(layer "B.Fab")
			(hide yes)
			(effects
				(font
					(size 1 1)
					(thickness 0.15)
				)
				(justify mirror)
			)
		)
		(property "License" "Apache-2.0"
			(at 0 0 0)
			(layer "B.Fab")
			(hide yes)
			(effects
				(font
					(size 1 1)
					(thickness 0.15)
				)
				(justify mirror)
			)
		)
		(property "MPN" "CR0402-FX-1003GLF"
			(at 0 0 0)
			(layer "B.Fab")
			(hide yes)
			(effects
				(font
					(size 1 1)
					(thickness 0.15)
				)
				(justify mirror)
			)
		)
		(property "Manufacturer" "Bourns"
			(at 0 0 0)
			(layer "B.Fab")
			(hide yes)
			(effects
				(font
					(size 1 1)
					(thickness 0.15)
				)
				(justify mirror)
			)
		)
		(property "Tolerance" "1%"
			(at 0 0 0)
			(layer "B.Fab")
			(hide yes)
			(effects
				(font
					(size 1 1)
					(thickness 0.15)
				)
				(justify mirror)
			)
		)
		(property "Val" "100k"
			(at 0 0 0)
			(layer "B.Fab")
			(hide yes)
			(effects
				(font
					(size 1 1)
					(thickness 0.15)
				)
				(justify mirror)
			)
		)
		(sheetname "CSI")
		(sheetfile "csi.kicad_sch")
		(attr smd)
		(fp_rect
			(start -0.925 0.47)
			(end 0.925 -0.47)
			(stroke
				(width 0.05)
				(type default)
			)
			(fill none)
			(layer "B.CrtYd")
		)
		(fp_rect
			(start -0.5 0.25)
			(end 0.5 -0.25)
			(stroke
				(width 0.15)
				(type solid)
			)
			(fill none)
			(layer "B.Fab")
		)
		(fp_text user "${REFERENCE}"
			(at -0.95 -3.168 180)
			(layer "B.Fab")
			(hide yes)
			(effects
				(font
					(size 0.7 0.7)
					(thickness 0.15)
				)
				(justify left bottom mirror)
			)
		)
		(fp_text user "Author: Antmicro"
			(at -0.95 -4.169 180)
			(layer "B.Fab")
			(hide yes)
			(effects
				(font
					(size 0.7 0.7)
					(thickness 0.15)
				)
				(justify left bottom mirror)
			)
		)
		(fp_text user "License: Apache-2.0"
			(at -0.95 -5.169 180)
			(layer "B.Fab")
			(hide yes)
			(effects
				(font
					(size 0.7 0.7)
					(thickness 0.15)
				)
				(justify left bottom mirror)
			)
		)
		(pad "1" smd roundrect
			(at -0.48 0)
			(size 0.59 0.64)
			(layers "B.Cu" "B.Paste" "B.Mask")
			(roundrect_rratio 0.25)
			(net 1 "GND")
			(pintype "passive")
		)
		(pad "2" smd roundrect
			(at 0.48 0)
			(size 0.59 0.64)
			(layers "B.Cu" "B.Paste" "B.Mask")
			(roundrect_rratio 0.25)
			(net 322 "CSIA_PEN")
			(pintype "passive")
		)
	)
	(footprint "antmicro-footprints:TP_SMD_0.75mm"
		(layer "B.Cu")
		(at 68.165 115.57 180)
		(property "Reference" "TP17"
			(at 0 0.6 0)
			(layer "B.SilkS")
			(hide yes)
			(effects
				(font
					(size 0.7 0.7)
					(thickness 0.15)
				)
				(justify left bottom mirror)
			)
		)
		(property "Value" "TP_0.75mm_SMD"
			(at 0 -1.2 0)
			(layer "B.Fab")
			(effects
				(font
					(size 0.7 0.7)
					(thickness 0.15)
				)
				(justify left bottom mirror)
			)
		)
		(property "Footprint" "antmicro-footprints:TP_SMD_0.75mm"
			(at 0 0 180)
			(layer "F.Fab")
			(hide yes)
			(effects
				(font
					(size 1.27 1.27)
					(thickness 0.15)
				)
			)
		)
		(property "Author" "Antmicro"
			(at 136.33 231.14 0)
			(layer "B.Fab")
			(hide yes)
			(effects
				(font
					(size 1 1)
					(thickness 0.15)
				)
				(justify mirror)
			)
		)
		(property "License" "Apache-2.0"
			(at 136.33 231.14 0)
			(layer "B.Fab")
			(hide yes)
			(effects
				(font
					(size 1 1)
					(thickness 0.15)
				)
				(justify mirror)
			)
		)
		(property "MPN" ""
			(at 136.33 231.14 0)
			(layer "B.Fab")
			(hide yes)
			(effects
				(font
					(size 1 1)
					(thickness 0.15)
				)
				(justify mirror)
			)
		)
		(property "Manufacturer" ""
			(at 136.33 231.14 0)
			(layer "B.Fab")
			(hide yes)
			(effects
				(font
					(size 1 1)
					(thickness 0.15)
				)
				(justify mirror)
			)
		)
		(sheetname "USB Debug, DP")
		(sheetfile "usb.kicad_sch")
		(attr exclude_from_pos_files exclude_from_bom)
		(fp_circle
			(center 0 0)
			(end 0.475 0)
			(stroke
				(width 0.05)
				(type default)
			)
			(fill none)
			(layer "B.CrtYd")
		)
		(fp_text user "Author: Antmicro"
			(at -0.4 -3.901 0)
			(layer "B.Fab")
			(hide yes)
			(effects
				(font
					(size 0.7 0.7)
					(thickness 0.15)
				)
				(justify left bottom mirror)
			)
		)
		(fp_text user "${REFERENCE}"
			(at -0.4 -2.7 0)
			(layer "B.Fab")
			(hide yes)
			(effects
				(font
					(size 0.7 0.7)
					(thickness 0.15)
				)
				(justify left bottom mirror)
			)
		)
		(fp_text user "License: Apache-2.0"
			(at -0.4 -5.101 0)
			(layer "B.Fab")
			(hide yes)
			(effects
				(font
					(size 0.7 0.7)
					(thickness 0.15)
				)
				(justify left bottom mirror)
			)
		)
		(pad "1" smd circle
			(at 0 0 180)
			(size 0.75 0.75)
			(layers "B.Cu" "B.Mask")
			(net 261 "/USB Debug, DP/USBC0_VBUS")
			(pinfunction "1")
			(pintype "passive")
		)
	)
	(footprint "antmicro-footprints:C_0603_1608Metric"
		(layer "B.Cu")
		(at 114.45 77.95 180)
		(descr "Capacitor SMD 0603")
		(tags "capacitor 0603")
		(property "Reference" "C21"
			(at -1.1 0.6 0)
			(layer "B.SilkS")
			(effects
				(font
					(size 0.7 0.7)
					(thickness 0.15)
				)
				(justify left bottom mirror)
			)
		)
		(property "Value" "C_10u_0603"
			(at 0 -1.6 0)
			(layer "B.Fab")
			(effects
				(font
					(size 0.7 0.7)
					(thickness 0.15)
				)
				(justify left bottom mirror)
			)
		)
		(property "Footprint" "antmicro-footprints:C_0603_1608Metric"
			(at 0 0 180)
			(layer "F.Fab")
			(hide yes)
			(effects
				(font
					(size 1.27 1.27)
					(thickness 0.15)
				)
			)
		)
		(property "Datasheet" "https://www.murata.com/products/productdetail?partno=GRM188R61A106KE69%23"
			(at 0 0 180)
			(layer "F.Fab")
			(hide yes)
			(effects
				(font
					(size 1.27 1.27)
					(thickness 0.15)
				)
			)
		)
		(property "Author" "Antmicro"
			(at 228.9 155.9 0)
			(layer "B.Fab")
			(hide yes)
			(effects
				(font
					(size 1 1)
					(thickness 0.15)
				)
				(justify mirror)
			)
		)
		(property "Dielectric" "template_dielectric"
			(at 228.9 155.9 0)
			(layer "B.Fab")
			(hide yes)
			(effects
				(font
					(size 1 1)
					(thickness 0.15)
				)
				(justify mirror)
			)
		)
		(property "License" "Apache-2.0"
			(at 228.9 155.9 0)
			(layer "B.Fab")
			(hide yes)
			(effects
				(font
					(size 1 1)
					(thickness 0.15)
				)
				(justify mirror)
			)
		)
		(property "MPN" "GRM188R61A106KE69D"
			(at 228.9 155.9 0)
			(layer "B.Fab")
			(hide yes)
			(effects
				(font
					(size 1 1)
					(thickness 0.15)
				)
				(justify mirror)
			)
		)
		(property "Manufacturer" "Murata"
			(at 228.9 155.9 0)
			(layer "B.Fab")
			(hide yes)
			(effects
				(font
					(size 1 1)
					(thickness 0.15)
				)
				(justify mirror)
			)
		)
		(property "Val" "10u"
			(at 228.9 155.9 0)
			(layer "B.Fab")
			(hide yes)
			(effects
				(font
					(size 1 1)
					(thickness 0.15)
				)
				(justify mirror)
			)
		)
		(property "Voltage" ""
			(at 228.9 155.9 0)
			(layer "B.Fab")
			(hide yes)
			(effects
				(font
					(size 1 1)
					(thickness 0.15)
				)
				(justify mirror)
			)
		)
		(sheetname "M.2")
		(sheetfile "m-2.kicad_sch")
		(attr smd)
		(fp_line
			(start 0.15 0.4)
			(end -0.15 0.4)
			(stroke
				(width 0.15)
				(type solid)
			)
			(layer "B.SilkS")
		)
		(fp_line
			(start 0.15 -0.4)
			(end -0.15 -0.4)
			(stroke
				(width 0.15)
				(type solid)
			)
			(layer "B.SilkS")
		)
		(fp_rect
			(start -1.25 0.65)
			(end 1.25 -0.65)
			(stroke
				(width 0.05)
				(type solid)
			)
			(fill none)
			(layer "B.CrtYd")
		)
		(fp_rect
			(start -0.8 0.4)
			(end 0.8 -0.4)
			(stroke
				(width 0.15)
				(type solid)
			)
			(fill none)
			(layer "B.Fab")
		)
		(fp_text user "Author: Antmicro"
			(at -1.682 -4.894 0)
			(layer "B.Fab")
			(hide yes)
			(effects
				(font
					(size 0.7 0.7)
					(thickness 0.15)
				)
				(justify left bottom mirror)
			)
		)
		(fp_text user "License: Apache-2.0"
			(at -1.682 -5.895 0)
			(layer "B.Fab")
			(hide yes)
			(effects
				(font
					(size 0.7 0.7)
					(thickness 0.15)
				)
				(justify left bottom mirror)
			)
		)
		(fp_text user "${REFERENCE}"
			(at -1.682 -3.895 0)
			(layer "B.Fab")
			(hide yes)
			(effects
				(font
					(size 0.7 0.7)
					(thickness 0.15)
				)
				(justify left bottom mirror)
			)
		)
		(pad "1" smd roundrect
			(at -0.7 0 180)
			(size 0.8 1)
			(layers "B.Cu" "B.Paste" "B.Mask")
			(roundrect_rratio 0.2)
			(net 635 "/M.2/3V3_M2")
			(pintype "passive")
		)
		(pad "2" smd roundrect
			(at 0.7 0 180)
			(size 0.8 1)
			(layers "B.Cu" "B.Paste" "B.Mask")
			(roundrect_rratio 0.2)
			(net 1 "GND")
			(pintype "passive")
		)
	)
	(footprint "antmicro-footprints:TSOT23-6"
		(layer "B.Cu")
		(at 97.52 81.75 -90)
		(property "Reference" "U27"
			(at -0.8 -2.71 90)
			(layer "B.SilkS")
			(effects
				(font
					(size 0.7 0.7)
					(thickness 0.15)
				)
				(justify left bottom mirror)
			)
		)
		(property "Value" "AP22615A_TSOT26"
			(at 0 -2.6 90)
			(layer "B.Fab")
			(effects
				(font
					(size 0.7 0.7)
					(thickness 0.15)
				)
				(justify left bottom mirror)
			)
		)
		(property "Footprint" "antmicro-footprints:TSOT23-6"
			(at 0 0 -90)
			(layer "F.Fab")
			(hide yes)
			(effects
				(font
					(size 1.27 1.27)
					(thickness 0.15)
				)
			)
		)
		(property "Datasheet" "https://www.mouser.com/datasheet/2/115/DIOD_S_A0008958405_1-2543193.pdf"
			(at 0 0 -90)
			(layer "F.Fab")
			(hide yes)
			(effects
				(font
					(size 1.27 1.27)
					(thickness 0.15)
				)
			)
		)
		(property "Author" "Antmicro"
			(at 15.77 179.27 0)
			(layer "B.Fab")
			(hide yes)
			(effects
				(font
					(size 1 1)
					(thickness 0.15)
				)
				(justify mirror)
			)
		)
		(property "License" "Apache-2.0"
			(at 15.77 179.27 0)
			(layer "B.Fab")
			(hide yes)
			(effects
				(font
					(size 1 1)
					(thickness 0.15)
				)
				(justify mirror)
			)
		)
		(property "MPN" "AP22615AWU-7"
			(at 15.77 179.27 0)
			(layer "B.Fab")
			(hide yes)
			(effects
				(font
					(size 1 1)
					(thickness 0.15)
				)
				(justify mirror)
			)
		)
		(property "Manufacturer" "Diodes Incorporated"
			(at 15.77 179.27 0)
			(layer "B.Fab")
			(hide yes)
			(effects
				(font
					(size 1 1)
					(thickness 0.15)
				)
				(justify mirror)
			)
		)
		(sheetname "CSI")
		(sheetfile "csi.kicad_sch")
		(attr smd)
		(fp_line
			(start -1 1.5)
			(end 1 1.497)
			(stroke
				(width 0.15)
				(type solid)
			)
			(layer "B.SilkS")
		)
		(fp_line
			(start -1 1.375)
			(end -1 1.5)
			(stroke
				(width 0.15)
				(type solid)
			)
			(layer "B.SilkS")
		)
		(fp_line
			(start 1 1.375)
			(end 1 1.497)
			(stroke
				(width 0.15)
				(type solid)
			)
			(layer "B.SilkS")
		)
		(fp_line
			(start -1 -1.4)
			(end -1 -1.55)
			(stroke
				(width 0.15)
				(type solid)
			)
			(layer "B.SilkS")
		)
		(fp_line
			(start 1 -1.4)
			(end 1 -1.55)
			(stroke
				(width 0.15)
				(type solid)
			)
			(layer "B.SilkS")
		)
		(fp_line
			(start -1 -1.55)
			(end 1 -1.55)
			(stroke
				(width 0.15)
				(type solid)
			)
			(layer "B.SilkS")
		)
		(fp_circle
			(center -1.44 1.5)
			(end -1.39 1.5)
			(stroke
				(width 0.15)
				(type solid)
			)
			(fill solid)
			(layer "B.SilkS")
		)
		(fp_rect
			(start 1.93 1.7)
			(end -1.93 -1.7)
			(stroke
				(width 0.05)
				(type solid)
			)
			(fill none)
			(layer "B.CrtYd")
		)
		(fp_line
			(start -0.876 1.096)
			(end -0.45 1.521)
			(stroke
				(width 0.15)
				(type solid)
			)
			(layer "B.Fab")
		)
		(fp_rect
			(start 0.875 -1.528)
			(end -0.875 1.525)
			(stroke
				(width 0.15)
				(type solid)
			)
			(fill none)
			(layer "B.Fab")
		)
		(fp_text user "Author: Antmicro"
			(at -1.93 -5 90)
			(layer "B.Fab")
			(hide yes)
			(effects
				(font
					(size 0.7 0.7)
					(thickness 0.15)
				)
				(justify left bottom mirror)
			)
		)
		(fp_text user "License: Apache-2.0"
			(at -1.93 -6.199 90)
			(layer "B.Fab")
			(hide yes)
			(effects
				(font
					(size 0.7 0.7)
					(thickness 0.15)
				)
				(justify left bottom mirror)
			)
		)
		(fp_text user "${REFERENCE}"
			(at -1.93 -3.8 90)
			(layer "B.Fab")
			(hide yes)
			(effects
				(font
					(size 0.7 0.7)
					(thickness 0.15)
				)
				(justify left bottom mirror)
			)
		)
		(pad "1" smd rect
			(at -1.301 0.947)
			(size 0.7 1.2)
			(layers "B.Cu" "B.Paste" "B.Mask")
			(net 111 "/CSI/CSIB_5V")
			(pinfunction "OUT")
			(pintype "power_out")
		)
		(pad "2" smd rect
			(at -1.301 -0.004)
			(size 0.7 1.2)
			(layers "B.Cu" "B.Paste" "B.Mask")
			(net 1 "GND")
			(pinfunction "GND")
			(pintype "power_in")
		)
		(pad "3" smd rect
			(at -1.301 -0.954)
			(size 0.7 1.2)
			(layers "B.Cu" "B.Paste" "B.Mask")
			(net 393 "CSIB_FLG")
			(pinfunction "FLG")
			(pintype "output")
		)
		(pad "4" smd rect
			(at 1.299 -0.954)
			(size 0.7 1.2)
			(layers "B.Cu" "B.Paste" "B.Mask")
			(net 338 "CSIB_PEN")
			(pinfunction "EN")
			(pintype "input")
		)
		(pad "5" smd rect
			(at 1.299 -0.004)
			(size 0.7 1.2)
			(layers "B.Cu" "B.Paste" "B.Mask")
			(net 343 "/CSI/CSIB_5V_ISET")
			(pinfunction "ISET")
			(pintype "passive")
		)
		(pad "6" smd rect
			(at 1.299 0.947)
			(size 0.7 1.2)
			(layers "B.Cu" "B.Paste" "B.Mask")
			(net 99 "+5V")
			(pinfunction "IN")
			(pintype "power_in")
		)
	)
	(footprint "antmicro-footprints:TP_SMD_0.75mm"
		(layer "B.Cu")
		(at 90.745 114.4 90)
		(property "Reference" "TP57"
			(at -1.855 -1.49 90)
			(layer "B.SilkS")
			(effects
				(font
					(size 0.7 0.7)
					(thickness 0.15)
				)
				(justify right bottom mirror)
			)
		)
		(property "Value" "TP_0.75mm_SMD"
			(at 0 -1.2 90)
			(layer "B.Fab")
			(effects
				(font
					(size 0.7 0.7)
					(thickness 0.15)
				)
				(justify right bottom mirror)
			)
		)
		(property "Footprint" "antmicro-footprints:TP_SMD_0.75mm"
			(at 0 0 90)
			(layer "F.Fab")
			(hide yes)
			(effects
				(font
					(size 1.27 1.27)
					(thickness 0.15)
				)
			)
		)
		(property "Author" "Antmicro"
			(at 205.145 23.655 0)
			(layer "B.Fab")
			(hide yes)
			(effects
				(font
					(size 1 1)
					(thickness 0.15)
				)
				(justify mirror)
			)
		)
		(property "License" "Apache-2.0"
			(at 205.145 23.655 0)
			(layer "B.Fab")
			(hide yes)
			(effects
				(font
					(size 1 1)
					(thickness 0.15)
				)
				(justify mirror)
			)
		)
		(property "MPN" ""
			(at 205.145 23.655 0)
			(layer "B.Fab")
			(hide yes)
			(effects
				(font
					(size 1 1)
					(thickness 0.15)
				)
				(justify mirror)
			)
		)
		(property "Manufacturer" ""
			(at 205.145 23.655 0)
			(layer "B.Fab")
			(hide yes)
			(effects
				(font
					(size 1 1)
					(thickness 0.15)
				)
				(justify mirror)
			)
		)
		(sheetname "HDMI")
		(sheetfile "hdmi.kicad_sch")
		(attr exclude_from_pos_files exclude_from_bom)
		(fp_circle
			(center 0 0)
			(end 0.475 0)
			(stroke
				(width 0.05)
				(type default)
			)
			(fill none)
			(layer "B.CrtYd")
		)
		(fp_text user "License: Apache-2.0"
			(at -0.4 -5.101 90)
			(layer "B.Fab")
			(hide yes)
			(effects
				(font
					(size 0.7 0.7)
					(thickness 0.15)
				)
				(justify right bottom mirror)
			)
		)
		(fp_text user "${REFERENCE}"
			(at -0.4 -2.7 90)
			(layer "B.Fab")
			(hide yes)
			(effects
				(font
					(size 0.7 0.7)
					(thickness 0.15)
				)
				(justify right bottom mirror)
			)
		)
		(fp_text user "Author: Antmicro"
			(at -0.4 -3.901 90)
			(layer "B.Fab")
			(hide yes)
			(effects
				(font
					(size 0.7 0.7)
					(thickness 0.15)
				)
				(justify right bottom mirror)
			)
		)
		(pad "1" smd circle
			(at 0 0 90)
			(size 0.75 0.75)
			(layers "B.Cu" "B.Mask")
			(net 555 "/HDMI/HDMI_SCL_3V3")
			(pinfunction "1")
			(pintype "passive")
		)
	)
	(footprint "antmicro-footprints:TP_SMD_0.75mm"
		(layer "B.Cu")
		(at 68.165 117.07 180)
		(property "Reference" "TP1"
			(at 0 0.6 0)
			(layer "B.SilkS")
			(hide yes)
			(effects
				(font
					(size 0.7 0.7)
					(thickness 0.15)
				)
				(justify left bottom mirror)
			)
		)
		(property "Value" "TP_0.75mm_SMD"
			(at 0 -1.2 0)
			(layer "B.Fab")
			(effects
				(font
					(size 0.7 0.7)
					(thickness 0.15)
				)
				(justify left bottom mirror)
			)
		)
		(property "Footprint" "antmicro-footprints:TP_SMD_0.75mm"
			(at 0 0 180)
			(layer "F.Fab")
			(hide yes)
			(effects
				(font
					(size 1.27 1.27)
					(thickness 0.15)
				)
			)
		)
		(property "Author" "Antmicro"
			(at 136.33 234.14 0)
			(layer "B.Fab")
			(hide yes)
			(effects
				(font
					(size 1 1)
					(thickness 0.15)
				)
				(justify mirror)
			)
		)
		(property "License" "Apache-2.0"
			(at 136.33 234.14 0)
			(layer "B.Fab")
			(hide yes)
			(effects
				(font
					(size 1 1)
					(thickness 0.15)
				)
				(justify mirror)
			)
		)
		(property "MPN" ""
			(at 136.33 234.14 0)
			(layer "B.Fab")
			(hide yes)
			(effects
				(font
					(size 1 1)
					(thickness 0.15)
				)
				(justify mirror)
			)
		)
		(property "Manufacturer" ""
			(at 136.33 234.14 0)
			(layer "B.Fab")
			(hide yes)
			(effects
				(font
					(size 1 1)
					(thickness 0.15)
				)
				(justify mirror)
			)
		)
		(sheetname "USB Debug, DP")
		(sheetfile "usb.kicad_sch")
		(attr exclude_from_pos_files exclude_from_bom)
		(fp_circle
			(center 0 0)
			(end 0.475 0)
			(stroke
				(width 0.05)
				(type default)
			)
			(fill none)
			(layer "B.CrtYd")
		)
		(fp_text user "${REFERENCE}"
			(at -0.4 -2.7 0)
			(layer "B.Fab")
			(hide yes)
			(effects
				(font
					(size 0.7 0.7)
					(thickness 0.15)
				)
				(justify left bottom mirror)
			)
		)
		(fp_text user "License: Apache-2.0"
			(at -0.4 -5.101 0)
			(layer "B.Fab")
			(hide yes)
			(effects
				(font
					(size 0.7 0.7)
					(thickness 0.15)
				)
				(justify left bottom mirror)
			)
		)
		(fp_text user "Author: Antmicro"
			(at -0.4 -3.901 0)
			(layer "B.Fab")
			(hide yes)
			(effects
				(font
					(size 0.7 0.7)
					(thickness 0.15)
				)
				(justify left bottom mirror)
			)
		)
		(pad "1" smd circle
			(at 0 0 180)
			(size 0.75 0.75)
			(layers "B.Cu" "B.Mask")
			(net 196 "/USB Debug, DP/USBC3_VBUS")
			(pinfunction "1")
			(pintype "passive")
		)
	)
)
